(kicad_pcb
	(version 20260206)
	(generator "pcbnew")
	(generator_version "10.0")
	(general
		(thickness 1.6)
		(legacy_teardrops no)
	)
	(paper "A4")
	(title_block
		(title "12092022_DA0F0TFB6D0_F0T_FAN_BOARD_MP5048_D_brd_v02_OCP.brd")
		(comment 1 "Grand Teton / footprints 321-327 of 924")
	)
	(layers
		(0 "F.Cu" signal "TOP")
		(4 "In1.Cu" signal "GND")
		(6 "In2.Cu" signal "IN1")
		(8 "In3.Cu" signal "IN2")
		(10 "In4.Cu" signal "GND1")
		(2 "B.Cu" signal "BOTTOM")
		(9 "F.Adhes" user "F.Adhesive")
		(11 "B.Adhes" user "B.Adhesive")
		(13 "F.Paste" user "Package Geometry/Pastemask Top")
		(15 "B.Paste" user "Package Geometry/Pastemask Bottom")
		(5 "F.SilkS" user "Ref Des/Silkscreen Top")
		(7 "B.SilkS" user "Ref Des/Silkscreen Bottom")
		(1 "F.Mask" user "Board Geometry/Soldermask Top")
		(3 "B.Mask" user "Board Geometry/Soldermask Bottom")
		(17 "Dwgs.User" user "User.Drawings")
		(19 "Cmts.User" user "User.Comments")
		(21 "Eco1.User" user "User.Eco1")
		(23 "Eco2.User" user "User.Eco2")
		(25 "Edge.Cuts" user "Board Geometry/Outline")
		(27 "Margin" user)
		(31 "F.CrtYd" user "Package Geometry/Place Bound Top")
		(29 "B.CrtYd" user "Package Geometry/Place Bound Bottom")
		(35 "F.Fab" user "Ref Des/Assembly Top")
		(33 "B.Fab" user "Ref Des/Assembly Bottom")
	)
	(footprint ""
		(layer "F.Cu")
		(at 5.08 -331.978)
		(property "Reference" "H15"
			(at -1.143 -3.02133 0)
			(unlocked yes)
			(layer "F.SilkS")
			(effects
				(font
					(size 0.7874 0.5842)
					(thickness 0.1524)
				)
				(justify left)
			)
		)
		(property "Value" ""
			(at 0 0 0)
			(layer "F.Fab")
			(effects
				(font
					(size 1.27 1.27)
				)
			)
		)
		(duplicate_pad_numbers_are_jumpers no)
		(fp_circle
			(center 0 0)
			(end 2.4003 0)
			(stroke
				(width 0.1524)
				(type default)
			)
			(fill no)
			(layer "F.SilkS")
		)
		(fp_circle
			(center 0 0)
			(end 6.5913 0)
			(stroke
				(width 0.1524)
				(type default)
			)
			(fill no)
			(layer "B.SilkS")
		)
		(fp_circle
			(center 0 0)
			(end 6.5913 0)
			(stroke
				(width 0.1)
				(type default)
			)
			(fill no)
			(layer "B.Fab")
		)
		(fp_circle
			(center 0 0)
			(end 2.4003 0)
			(stroke
				(width 0.1)
				(type default)
			)
			(fill no)
			(layer "F.Fab")
		)
		(pad "" np_thru_hole circle
			(at 0 0)
			(size 3.175 3.175)
			(drill 3.175)
			(layers "*.Cu" "*.Mask")
			(clearance 0.381)
			(thermal_gap 0.381)
		)
		(zone
			(layers "F.Cu" "B.Cu" "In1.Cu" "In2.Cu" "In3.Cu" "In4.Cu")
			(hatch none 0.5)
			(connect_pads
				(clearance 0)
			)
			(min_thickness 0.25)
			(keepout
				(tracks not_allowed)
				(vias allowed)
				(pads allowed)
				(copperpour not_allowed)
				(footprints allowed)
			)
			(placement
				(enabled no)
				(sheetname "")
			)
			(fill
				(thermal_gap 0.5)
				(thermal_bridge_width 0.5)
				(island_removal_mode 0)
			)
			(polygon
				(pts
					(arc
						(start 7.1755 -331.978)
						(mid 2.9845 -331.978)
						(end 7.1755 -331.978)
					)
				)
			)
		)
	)
	(footprint ""
		(layer "F.Cu")
		(at 18.679922 -194.250056 180)
		(property "Reference" "D255"
			(at 0.772922 -1.236726 0)
			(unlocked yes)
			(layer "F.SilkS")
			(effects
				(font
					(size 0.7874 0.5842)
					(thickness 0.1524)
				)
				(justify left)
			)
		)
		(property "Value" ""
			(at 0 0 180)
			(layer "F.Fab")
			(effects
				(font
					(size 1.27 1.27)
				)
			)
		)
		(duplicate_pad_numbers_are_jumpers no)
		(fp_line
			(start 0.94488 0.450088)
			(end 0.94488 -0.450088)
			(stroke
				(width 0.1524)
				(type default)
			)
			(layer "F.SilkS")
		)
		(fp_line
			(start 0.94488 -0.450088)
			(end -0.854964 -0.450088)
			(stroke
				(width 0.1524)
				(type default)
			)
			(layer "F.SilkS")
		)
		(fp_line
			(start 0.870458 -0.2794)
			(end 0.845058 0.4064)
			(stroke
				(width 0.1524)
				(type default)
			)
			(layer "F.SilkS")
		)
		(fp_line
			(start 0.845058 0.4064)
			(end 0.845058 -0.381)
			(stroke
				(width 0.1524)
				(type default)
			)
			(layer "F.SilkS")
		)
		(fp_line
			(start -0.854964 0.450088)
			(end 0.925068 0.450088)
			(stroke
				(width 0.1524)
				(type default)
			)
			(layer "F.SilkS")
		)
		(fp_line
			(start -0.854964 -0.450088)
			(end -0.854964 0.450088)
			(stroke
				(width 0.1524)
				(type default)
			)
			(layer "F.SilkS")
		)
		(fp_line
			(start 0.54991 0.350012)
			(end 0.54991 -0.350012)
			(stroke
				(width 0.1)
				(type default)
			)
			(layer "F.Fab")
		)
		(fp_line
			(start 0.54991 -0.350012)
			(end -0.54991 -0.350012)
			(stroke
				(width 0.1)
				(type default)
			)
			(layer "F.Fab")
		)
		(fp_line
			(start -0.54991 0.350012)
			(end 0.54991 0.350012)
			(stroke
				(width 0.1)
				(type default)
			)
			(layer "F.Fab")
		)
		(fp_line
			(start -0.54991 -0.350012)
			(end -0.54991 0.350012)
			(stroke
				(width 0.1)
				(type default)
			)
			(layer "F.Fab")
		)
		(fp_text user "-"
			(at 2.169922 -0.733806 0)
			(unlocked yes)
			(layer "F.SilkS")
			(effects
				(font
					(size 1.905 1.4224)
					(thickness 0.1524)
				)
				(justify left)
			)
		)
		(fp_text user "+"
			(at -1.005078 0.028194 0)
			(unlocked yes)
			(layer "F.SilkS")
			(effects
				(font
					(size 1.905 1.4224)
					(thickness 0.1524)
				)
				(justify left)
			)
		)
		(fp_text user "-"
			(at 2.48539 0.239014 0)
			(unlocked yes)
			(layer "F.Fab")
			(effects
				(font
					(size 1.905 1.4224)
					(thickness 0.1524)
				)
				(justify left)
			)
		)
		(fp_text user "+"
			(at -0.808228 0.239014 0)
			(unlocked yes)
			(layer "F.Fab")
			(effects
				(font
					(size 1.905 1.4224)
					(thickness 0.1524)
				)
				(justify left)
			)
		)
		(pad "A" smd rect
			(at -0.424942 0 180)
			(size 0.5588 0.6096)
			(layers "F.Cu" "F.Mask" "F.Paste")
			(net "GND")
		)
		(pad "C" smd rect
			(at 0.424942 0)
			(size 0.5588 0.6096)
			(layers "F.Cu" "F.Mask" "F.Paste")
			(net "FAN_6_PWM_OL_R")
		)
	)
	(footprint ""
		(layer "F.Cu")
		(at 20.828 -175.768 180)
		(property "Reference" "R5672"
			(at 0 0 180)
			(layer "F.SilkS")
			(hide yes)
			(effects
				(font
					(size 1.27 1.27)
				)
			)
		)
		(property "Value" ""
			(at 0 0 180)
			(layer "F.Fab")
			(effects
				(font
					(size 1.27 1.27)
				)
			)
		)
		(duplicate_pad_numbers_are_jumpers no)
		(fp_line
			(start 0.7874 0.4064)
			(end -0.7874 0.4064)
			(stroke
				(width 0.1524)
				(type default)
			)
			(layer "F.SilkS")
		)
		(fp_line
			(start 0.7874 -0.4064)
			(end 0.7874 0.4064)
			(stroke
				(width 0.1524)
				(type default)
			)
			(layer "F.SilkS")
		)
		(fp_line
			(start -0.7874 0.4064)
			(end -0.7874 -0.4064)
			(stroke
				(width 0.1524)
				(type default)
			)
			(layer "F.SilkS")
		)
		(fp_line
			(start -0.7874 -0.4064)
			(end 0.7874 -0.4064)
			(stroke
				(width 0.1524)
				(type default)
			)
			(layer "F.SilkS")
		)
		(fp_line
			(start 0.67945 0.3048)
			(end 0.120396 0.3048)
			(stroke
				(width 0.1)
				(type default)
			)
			(layer "F.Fab")
		)
		(fp_line
			(start 0.67945 -0.3048)
			(end 0.67945 0.3048)
			(stroke
				(width 0.1)
				(type default)
			)
			(layer "F.Fab")
		)
		(fp_line
			(start 0.12065 -0.2794)
			(end 0.12065 -0.3048)
			(stroke
				(width 0.1)
				(type default)
			)
			(layer "F.Fab")
		)
		(fp_line
			(start 0.12065 -0.3048)
			(end 0.67945 -0.3048)
			(stroke
				(width 0.1)
				(type default)
			)
			(layer "F.Fab")
		)
		(fp_line
			(start 0.120396 0.3048)
			(end 0.120396 0.2794)
			(stroke
				(width 0.1)
				(type default)
			)
			(layer "F.Fab")
		)
		(fp_line
			(start 0.120396 0.2794)
			(end -0.12065 0.2794)
			(stroke
				(width 0.1)
				(type default)
			)
			(layer "F.Fab")
		)
		(fp_line
			(start -0.12065 0.3048)
			(end -0.67945 0.3048)
			(stroke
				(width 0.1)
				(type default)
			)
			(layer "F.Fab")
		)
		(fp_line
			(start -0.12065 0.2794)
			(end -0.12065 0.3048)
			(stroke
				(width 0.1)
				(type default)
			)
			(layer "F.Fab")
		)
		(fp_line
			(start -0.12065 -0.2794)
			(end 0.12065 -0.2794)
			(stroke
				(width 0.1)
				(type default)
			)
			(layer "F.Fab")
		)
		(fp_line
			(start -0.12065 -0.305054)
			(end -0.12065 -0.2794)
			(stroke
				(width 0.1)
				(type default)
			)
			(layer "F.Fab")
		)
		(fp_line
			(start -0.67945 0.3048)
			(end -0.67945 -0.305054)
			(stroke
				(width 0.1)
				(type default)
			)
			(layer "F.Fab")
		)
		(fp_line
			(start -0.67945 -0.305054)
			(end -0.12065 -0.305054)
			(stroke
				(width 0.1)
				(type default)
			)
			(layer "F.Fab")
		)
		(pad "1" smd circle
			(at -0.40005 0 180)
			(size 0 0)
			(layers "F.Cu" "F.Mask" "F.Paste")
			(net "P3V3_AUX")
		)
		(pad "2" smd circle
			(at 0.40005 0 180)
			(size 0 0)
			(layers "F.Cu" "F.Mask" "F.Paste")
			(net "FM_BOARD_SKU_ID2")
		)
	)
	(footprint ""
		(layer "F.Cu")
		(at 30.734 -160.02 90)
		(property "Reference" "R4878"
			(at 0 0 90)
			(layer "F.SilkS")
			(hide yes)
			(effects
				(font
					(size 1.27 1.27)
				)
			)
		)
		(property "Value" ""
			(at 0 0 90)
			(layer "F.Fab")
			(effects
				(font
					(size 1.27 1.27)
				)
			)
		)
		(duplicate_pad_numbers_are_jumpers no)
		(fp_line
			(start 0.7874 -0.4064)
			(end 0.7874 0.4064)
			(stroke
				(width 0.1524)
				(type default)
			)
			(layer "F.SilkS")
		)
		(fp_line
			(start -0.7874 -0.4064)
			(end 0.7874 -0.4064)
			(stroke
				(width 0.1524)
				(type default)
			)
			(layer "F.SilkS")
		)
		(fp_line
			(start 0.7874 0.4064)
			(end -0.7874 0.4064)
			(stroke
				(width 0.1524)
				(type default)
			)
			(layer "F.SilkS")
		)
		(fp_line
			(start -0.7874 0.4064)
			(end -0.7874 -0.4064)
			(stroke
				(width 0.1524)
				(type default)
			)
			(layer "F.SilkS")
		)
		(fp_line
			(start -0.12065 -0.305054)
			(end -0.12065 -0.2794)
			(stroke
				(width 0.1)
				(type default)
			)
			(layer "F.Fab")
		)
		(fp_line
			(start -0.67945 -0.305054)
			(end -0.12065 -0.305054)
			(stroke
				(width 0.1)
				(type default)
			)
			(layer "F.Fab")
		)
		(fp_line
			(start 0.67945 -0.3048)
			(end 0.67945 0.3048)
			(stroke
				(width 0.1)
				(type default)
			)
			(layer "F.Fab")
		)
		(fp_line
			(start 0.12065 -0.3048)
			(end 0.67945 -0.3048)
			(stroke
				(width 0.1)
				(type default)
			)
			(layer "F.Fab")
		)
		(fp_line
			(start 0.12065 -0.2794)
			(end 0.12065 -0.3048)
			(stroke
				(width 0.1)
				(type default)
			)
			(layer "F.Fab")
		)
		(fp_line
			(start -0.12065 -0.2794)
			(end 0.12065 -0.2794)
			(stroke
				(width 0.1)
				(type default)
			)
			(layer "F.Fab")
		)
		(fp_line
			(start 0.120396 0.2794)
			(end -0.12065 0.2794)
			(stroke
				(width 0.1)
				(type default)
			)
			(layer "F.Fab")
		)
		(fp_line
			(start -0.12065 0.2794)
			(end -0.12065 0.3048)
			(stroke
				(width 0.1)
				(type default)
			)
			(layer "F.Fab")
		)
		(fp_line
			(start 0.67945 0.3048)
			(end 0.120396 0.3048)
			(stroke
				(width 0.1)
				(type default)
			)
			(layer "F.Fab")
		)
		(fp_line
			(start 0.120396 0.3048)
			(end 0.120396 0.2794)
			(stroke
				(width 0.1)
				(type default)
			)
			(layer "F.Fab")
		)
		(fp_line
			(start -0.12065 0.3048)
			(end -0.67945 0.3048)
			(stroke
				(width 0.1)
				(type default)
			)
			(layer "F.Fab")
		)
		(fp_line
			(start -0.67945 0.3048)
			(end -0.67945 -0.305054)
			(stroke
				(width 0.1)
				(type default)
			)
			(layer "F.Fab")
		)
		(pad "1" smd circle
			(at -0.40005 0 90)
			(size 0 0)
			(layers "F.Cu" "F.Mask" "F.Paste")
			(net "SMB_FAN5_R_SDA")
		)
		(pad "2" smd circle
			(at 0.40005 0 90)
			(size 0 0)
			(layers "F.Cu" "F.Mask" "F.Paste")
			(net "SMB_FAN5_SDA")
		)
	)
	(footprint ""
		(layer "F.Cu")
		(at 20.828 -180.213)
		(property "Reference" "R5688"
			(at 0 0 0)
			(layer "F.SilkS")
			(hide yes)
			(effects
				(font
					(size 1.27 1.27)
				)
			)
		)
		(property "Value" ""
			(at 0 0 0)
			(layer "F.Fab")
			(effects
				(font
					(size 1.27 1.27)
				)
			)
		)
		(duplicate_pad_numbers_are_jumpers no)
		(fp_line
			(start -0.7874 -0.4064)
			(end 0.7874 -0.4064)
			(stroke
				(width 0.1524)
				(type default)
			)
			(layer "F.SilkS")
		)
		(fp_line
			(start -0.7874 0.4064)
			(end -0.7874 -0.4064)
			(stroke
				(width 0.1524)
				(type default)
			)
			(layer "F.SilkS")
		)
		(fp_line
			(start 0.7874 -0.4064)
			(end 0.7874 0.4064)
			(stroke
				(width 0.1524)
				(type default)
			)
			(layer "F.SilkS")
		)
		(fp_line
			(start 0.7874 0.4064)
			(end -0.7874 0.4064)
			(stroke
				(width 0.1524)
				(type default)
			)
			(layer "F.SilkS")
		)
		(fp_line
			(start -0.67945 -0.305054)
			(end -0.12065 -0.305054)
			(stroke
				(width 0.1)
				(type default)
			)
			(layer "F.Fab")
		)
		(fp_line
			(start -0.67945 0.3048)
			(end -0.67945 -0.305054)
			(stroke
				(width 0.1)
				(type default)
			)
			(layer "F.Fab")
		)
		(fp_line
			(start -0.12065 -0.305054)
			(end -0.12065 -0.2794)
			(stroke
				(width 0.1)
				(type default)
			)
			(layer "F.Fab")
		)
		(fp_line
			(start -0.12065 -0.2794)
			(end 0.12065 -0.2794)
			(stroke
				(width 0.1)
				(type default)
			)
			(layer "F.Fab")
		)
		(fp_line
			(start -0.12065 0.2794)
			(end -0.12065 0.3048)
			(stroke
				(width 0.1)
				(type default)
			)
			(layer "F.Fab")
		)
		(fp_line
			(start -0.12065 0.3048)
			(end -0.67945 0.3048)
			(stroke
				(width 0.1)
				(type default)
			)
			(layer "F.Fab")
		)
		(fp_line
			(start 0.120396 0.2794)
			(end -0.12065 0.2794)
			(stroke
				(width 0.1)
				(type default)
			)
			(layer "F.Fab")
		)
		(fp_line
			(start 0.120396 0.3048)
			(end 0.120396 0.2794)
			(stroke
				(width 0.1)
				(type default)
			)
			(layer "F.Fab")
		)
		(fp_line
			(start 0.12065 -0.3048)
			(end 0.67945 -0.3048)
			(stroke
				(width 0.1)
				(type default)
			)
			(layer "F.Fab")
		)
		(fp_line
			(start 0.12065 -0.2794)
			(end 0.12065 -0.3048)
			(stroke
				(width 0.1)
				(type default)
			)
			(layer "F.Fab")
		)
		(fp_line
			(start 0.67945 -0.3048)
			(end 0.67945 0.3048)
			(stroke
				(width 0.1)
				(type default)
			)
			(layer "F.Fab")
		)
		(fp_line
			(start 0.67945 0.3048)
			(end 0.120396 0.3048)
			(stroke
				(width 0.1)
				(type default)
			)
			(layer "F.Fab")
		)
		(pad "1" smd circle
			(at -0.40005 0)
			(size 0 0)
			(layers "F.Cu" "F.Mask" "F.Paste")
			(net "FM_BOARD_ID2")
		)
		(pad "2" smd circle
			(at 0.40005 0)
			(size 0 0)
			(layers "F.Cu" "F.Mask" "F.Paste")
			(net "GND")
		)
	)
	(footprint ""
		(layer "F.Cu")
		(at 12.954 -74.422)
		(property "Reference" "PR59"
			(at 0 0 0)
			(layer "F.SilkS")
			(hide yes)
			(effects
				(font
					(size 1.27 1.27)
				)
			)
		)
		(property "Value" ""
			(at 0 0 0)
			(layer "F.Fab")
			(effects
				(font
					(size 1.27 1.27)
				)
			)
		)
		(duplicate_pad_numbers_are_jumpers no)
		(fp_line
			(start -0.7874 -0.4064)
			(end 0.7874 -0.4064)
			(stroke
				(width 0.1524)
				(type default)
			)
			(layer "F.SilkS")
		)
		(fp_line
			(start -0.7874 0.4064)
			(end -0.7874 -0.4064)
			(stroke
				(width 0.1524)
				(type default)
			)
			(layer "F.SilkS")
		)
		(fp_line
			(start 0.7874 -0.4064)
			(end 0.7874 0.4064)
			(stroke
				(width 0.1524)
				(type default)
			)
			(layer "F.SilkS")
		)
		(fp_line
			(start 0.7874 0.4064)
			(end -0.7874 0.4064)
			(stroke
				(width 0.1524)
				(type default)
			)
			(layer "F.SilkS")
		)
		(fp_line
			(start -0.67945 -0.305054)
			(end -0.12065 -0.305054)
			(stroke
				(width 0.1)
				(type default)
			)
			(layer "F.Fab")
		)
		(fp_line
			(start -0.67945 0.3048)
			(end -0.67945 -0.305054)
			(stroke
				(width 0.1)
				(type default)
			)
			(layer "F.Fab")
		)
		(fp_line
			(start -0.12065 -0.305054)
			(end -0.12065 -0.2794)
			(stroke
				(width 0.1)
				(type default)
			)
			(layer "F.Fab")
		)
		(fp_line
			(start -0.12065 -0.2794)
			(end 0.12065 -0.2794)
			(stroke
				(width 0.1)
				(type default)
			)
			(layer "F.Fab")
		)
		(fp_line
			(start -0.12065 0.2794)
			(end -0.12065 0.3048)
			(stroke
				(width 0.1)
				(type default)
			)
			(layer "F.Fab")
		)
		(fp_line
			(start -0.12065 0.3048)
			(end -0.67945 0.3048)
			(stroke
				(width 0.1)
				(type default)
			)
			(layer "F.Fab")
		)
		(fp_line
			(start 0.120396 0.2794)
			(end -0.12065 0.2794)
			(stroke
				(width 0.1)
				(type default)
			)
			(layer "F.Fab")
		)
		(fp_line
			(start 0.120396 0.3048)
			(end 0.120396 0.2794)
			(stroke
				(width 0.1)
				(type default)
			)
			(layer "F.Fab")
		)
		(fp_line
			(start 0.12065 -0.3048)
			(end 0.67945 -0.3048)
			(stroke
				(width 0.1)
				(type default)
			)
			(layer "F.Fab")
		)
		(fp_line
			(start 0.12065 -0.2794)
			(end 0.12065 -0.3048)
			(stroke
				(width 0.1)
				(type default)
			)
			(layer "F.Fab")
		)
		(fp_line
			(start 0.67945 -0.3048)
			(end 0.67945 0.3048)
			(stroke
				(width 0.1)
				(type default)
			)
			(layer "F.Fab")
		)
		(fp_line
			(start 0.67945 0.3048)
			(end 0.120396 0.3048)
			(stroke
				(width 0.1)
				(type default)
			)
			(layer "F.Fab")
		)
		(pad "1" smd circle
			(at -0.40005 0)
			(size 0 0)
			(layers "F.Cu" "F.Mask" "F.Paste")
			(net "FAN_5_MODE")
		)
		(pad "2" smd circle
			(at 0.40005 0)
			(size 0 0)
			(layers "F.Cu" "F.Mask" "F.Paste")
			(net "GND")
		)
	)
	(footprint ""
		(layer "F.Cu")
		(at 15.504922 -32.217868 180)
		(property "Reference" "D241"
			(at 6.056122 0.000762 0)
			(unlocked yes)
			(layer "F.SilkS")
			(effects
				(font
					(size 0.7874 0.5842)
					(thickness 0.1524)
				)
				(justify left)
			)
		)
		(property "Value" ""
			(at 0 0 180)
			(layer "F.Fab")
			(effects
				(font
					(size 1.27 1.27)
				)
			)
		)
		(duplicate_pad_numbers_are_jumpers no)
		(fp_line
			(start 0.94488 0.450088)
			(end 0.94488 -0.450088)
			(stroke
				(width 0.1524)
				(type default)
			)
			(layer "F.SilkS")
		)
		(fp_line
			(start 0.94488 -0.450088)
			(end -0.854964 -0.450088)
			(stroke
				(width 0.1524)
				(type default)
			)
			(layer "F.SilkS")
		)
		(fp_line
			(start 0.870458 -0.2794)
			(end 0.845058 0.4064)
			(stroke
				(width 0.1524)
				(type default)
			)
			(layer "F.SilkS")
		)
		(fp_line
			(start 0.845058 0.4064)
			(end 0.845058 -0.381)
			(stroke
				(width 0.1524)
				(type default)
			)
			(layer "F.SilkS")
		)
		(fp_line
			(start -0.854964 0.450088)
			(end 0.925068 0.450088)
			(stroke
				(width 0.1524)
				(type default)
			)
			(layer "F.SilkS")
		)
		(fp_line
			(start -0.854964 -0.450088)
			(end -0.854964 0.450088)
			(stroke
				(width 0.1524)
				(type default)
			)
			(layer "F.SilkS")
		)
		(fp_line
			(start 0.54991 0.350012)
			(end 0.54991 -0.350012)
			(stroke
				(width 0.1)
				(type default)
			)
			(layer "F.Fab")
		)
		(fp_line
			(start 0.54991 -0.350012)
			(end -0.54991 -0.350012)
			(stroke
				(width 0.1)
				(type default)
			)
			(layer "F.Fab")
		)
		(fp_line
			(start -0.54991 0.350012)
			(end 0.54991 0.350012)
			(stroke
				(width 0.1)
				(type default)
			)
			(layer "F.Fab")
		)
		(fp_line
			(start -0.54991 -0.350012)
			(end -0.54991 0.350012)
			(stroke
				(width 0.1)
				(type default)
			)
			(layer "F.Fab")
		)
		(fp_text user "-"
			(at 2.48539 0.239014 0)
			(unlocked yes)
			(layer "F.SilkS")
			(effects
				(font
					(size 1.905 1.4224)
					(thickness 0.1524)
				)
				(justify left)
			)
		)
		(fp_text user "+"
			(at 0.264922 1.278382 0)
			(unlocked yes)
			(layer "F.SilkS")
			(effects
				(font
					(size 1.905 1.4224)
					(thickness 0.1524)
				)
				(justify left)
			)
		)
		(fp_text user "-"
			(at 2.48539 0.239014 0)
			(unlocked yes)
			(layer "F.Fab")
			(effects
				(font
					(size 1.905 1.4224)
					(thickness 0.1524)
				)
				(justify left)
			)
		)
		(fp_text user "+"
			(at -0.808228 0.239014 0)
			(unlocked yes)
			(layer "F.Fab")
			(effects
				(font
					(size 1.905 1.4224)
					(thickness 0.1524)
				)
				(justify left)
			)
		)
		(pad "A" smd rect
			(at -0.424942 0 180)
			(size 0.5588 0.6096)
			(layers "F.Cu" "F.Mask" "F.Paste")
			(net "GND")
		)
		(pad "C" smd rect
			(at 0.424942 0)
			(size 0.5588 0.6096)
			(layers "F.Cu" "F.Mask" "F.Paste")
			(net "FAN_4_TACH_OL_D")
		)
	)
)
